(kicad_pcb
	(version 20260206)
	(generator "pcbnew")
	(generator_version "10.0")
	(general
		(thickness 1.6)
		(legacy_teardrops no)
	)
	(paper "A4")
	(title_block
		(title "03242023_DA0F0TMBIJ0_F0T_Motherboard_J_brd_V01_OCP.brd")
		(comment 1 "Grand Teton / footprint 1187 of 6105 (U249), pads 1-104 of 484")
	)
	(layers
		(0 "F.Cu" signal "TOP")
		(4 "In1.Cu" signal "GND")
		(6 "In2.Cu" signal "IN1")
		(8 "In3.Cu" signal "GND1")
		(10 "In4.Cu" signal "IN2")
		(12 "In5.Cu" signal "GND2")
		(14 "In6.Cu" signal "IN3")
		(16 "In7.Cu" signal "GND3")
		(18 "In8.Cu" signal "VCC")
		(20 "In9.Cu" signal "VCC1")
		(22 "In10.Cu" signal "GND4")
		(24 "In11.Cu" signal "IN4")
		(26 "In12.Cu" signal "GND5")
		(28 "In13.Cu" signal "IN5")
		(30 "In14.Cu" signal "GND6")
		(32 "In15.Cu" signal "IN6")
		(34 "In16.Cu" signal "GND7")
		(2 "B.Cu" signal "BOTTOM")
		(9 "F.Adhes" user "F.Adhesive")
		(11 "B.Adhes" user "B.Adhesive")
		(13 "F.Paste" user "Package Geometry/Pastemask Top")
		(15 "B.Paste" user "Package Geometry/Pastemask Bottom")
		(5 "F.SilkS" user "Ref Des/Silkscreen Top")
		(7 "B.SilkS" user "Ref Des/Silkscreen Bottom")
		(1 "F.Mask" user "Board Geometry/Soldermask Top")
		(3 "B.Mask" user "Board Geometry/Soldermask Bottom")
		(17 "Dwgs.User" user "User.Drawings")
		(19 "Cmts.User" user "User.Comments")
		(21 "Eco1.User" user "User.Eco1")
		(23 "Eco2.User" user "User.Eco2")
		(25 "Edge.Cuts" user "Board Geometry/Outline")
		(27 "Margin" user)
		(31 "F.CrtYd" user "Package Geometry/Place Bound Top")
		(29 "B.CrtYd" user "Package Geometry/Place Bound Bottom")
		(35 "F.Fab" user "Ref Des/Assembly Top")
		(33 "B.Fab" user "Ref Des/Assembly Bottom")
	)
	(footprint ""
		(layer "F.Cu")
		(at 178.55565 -113.37544 90)
		(property "Reference" "U249"
			(at -11.966194 -11.833098 0)
			(unlocked yes)
			(layer "F.SilkS")
			(effects
				(font
					(size 0.7874 0.5842)
					(thickness 0.1524)
				)
				(justify left)
			)
		)
		(property "Value" ""
			(at 0 0 90)
			(layer "F.Fab")
			(effects
				(font
					(size 1.27 1.27)
				)
			)
		)
		(duplicate_pad_numbers_are_jumpers no)
		(pad "A1" smd circle
			(at -8.400034 -8.400034 90)
			(size 0.4064 0.4064)
			(layers "F.Cu" "F.Mask" "F.Paste")
			(net "GND")
		)
		(pad "A2" smd circle
			(at -7.599934 -8.400034 90)
			(size 0.4064 0.4064)
			(layers "F.Cu" "F.Mask" "F.Paste")
			(net "FM_GPU_PWR_EN")
		)
		(pad "A3" smd circle
			(at -6.800088 -8.400034 90)
			(size 0.4064 0.4064)
			(layers "F.Cu" "F.Mask" "F.Paste")
			(net "FM_GPU_HSC_EN_R")
		)
		(pad "A4" smd circle
			(at -5.999988 -8.400034 90)
			(size 0.4064 0.4064)
			(layers "F.Cu" "F.Mask" "F.Paste")
			(net "SMB_BMC_SWB_EN")
		)
		(pad "A5" smd circle
			(at -5.199888 -8.400034 90)
			(size 0.4064 0.4064)
			(layers "F.Cu" "F.Mask" "F.Paste")
			(net "FM_TPM_PRSNT_R_N")
		)
		(pad "A6" smd circle
			(at -4.400042 -8.400034 90)
			(size 0.4064 0.4064)
			(layers "F.Cu" "F.Mask" "F.Paste")
			(net "FM_PECI_MUX_SEL_N")
		)
		(pad "A7" smd circle
			(at -3.599942 -8.400034 90)
			(size 0.4064 0.4064)
			(layers "F.Cu" "F.Mask" "F.Paste")
			(net "FM_OCP_SFF_PWR_GOOD_R")
		)
		(pad "A8" smd circle
			(at -2.800096 -8.400034 90)
			(size 0.4064 0.4064)
			(layers "F.Cu" "F.Mask" "F.Paste")
			(net "IRQ_SML1_PMBUS_PLD_ALERT_N")
		)
		(pad "A9" smd circle
			(at -1.999996 -8.400034 90)
			(size 0.4064 0.4064)
			(layers "F.Cu" "F.Mask" "F.Paste")
			(net "GPU_NVS_PWR_BRAKE_R_N")
		)
		(pad "A10" smd circle
			(at -1.199896 -8.400034 90)
			(size 0.4064 0.4064)
			(layers "F.Cu" "F.Mask" "F.Paste")
			(net "SMB_HOST_3V3AUX_PLD_SCL")
		)
		(pad "A11" smd circle
			(at -0.40005 -8.400034 90)
			(size 0.4064 0.4064)
			(layers "F.Cu" "F.Mask" "F.Paste")
			(net "GPU_WP_HW_CTRL_R_N")
		)
		(pad "A12" smd circle
			(at 0.40005 -8.400034 90)
			(size 0.4064 0.4064)
			(layers "F.Cu" "F.Mask" "F.Paste")
			(net "SMB_1_PLD_3V3AUX_SDA_R1")
		)
		(pad "A13" smd circle
			(at 1.199896 -8.400034 90)
			(size 0.4064 0.4064)
			(layers "F.Cu" "F.Mask" "F.Paste")
			(net "PWRGD_PVNN_MAIN_CPU0")
		)
		(pad "A14" smd circle
			(at 1.999996 -8.400034 90)
			(size 0.4064 0.4064)
			(layers "F.Cu" "F.Mask" "F.Paste")
			(net "PWRGD_PVPP_HBM_CPU1")
		)
		(pad "A15" smd circle
			(at 2.800096 -8.400034 90)
			(size 0.4064 0.4064)
			(layers "F.Cu" "F.Mask" "F.Paste")
			(net "SGPIO_DEBUG_PLD_DOUT")
		)
		(pad "A16" smd circle
			(at 3.599942 -8.400034 90)
			(size 0.4064 0.4064)
			(layers "F.Cu" "F.Mask" "F.Paste")
			(net "SGPIO_OCP_SFF_DATAOUT")
		)
		(pad "A17" smd circle
			(at 4.400042 -8.400034 90)
			(size 0.4064 0.4064)
			(layers "F.Cu" "F.Mask" "F.Paste")
			(net "SGPIO_OCP_V3_2_DATAOUT")
		)
		(pad "A18" smd circle
			(at 5.199888 -8.400034 90)
			(size 0.4064 0.4064)
			(layers "F.Cu" "F.Mask" "F.Paste")
			(net "GPU_FPGA_READY_ISO_R")
		)
		(pad "A19" smd circle
			(at 5.999988 -8.400034 90)
			(size 0.4064 0.4064)
			(layers "F.Cu" "F.Mask" "F.Paste")
			(net "P12V_HSC_TEMP_ALERT_R_N")
		)
		(pad "A20" smd circle
			(at 6.800088 -8.400034 90)
			(size 0.4064 0.4064)
			(layers "F.Cu" "F.Mask" "F.Paste")
			(net "NC_FPGA_PT43A")
		)
		(pad "A21" smd circle
			(at 7.599934 -8.400034 90)
			(size 0.4064 0.4064)
			(layers "F.Cu" "F.Mask" "F.Paste")
			(net "NC_FPGA_PT44A")
		)
		(pad "A22" smd circle
			(at 8.400034 -8.400034 90)
			(size 0.4064 0.4064)
			(layers "F.Cu" "F.Mask" "F.Paste")
			(net "GND")
		)
		(pad "AA1" smd circle
			(at -8.400034 7.599934 90)
			(size 0.4064 0.4064)
			(layers "F.Cu" "F.Mask" "F.Paste")
			(net "H_CPU_NMI_LVC1_R_N")
		)
		(pad "AA2" smd circle
			(at -7.599934 7.599934 90)
			(size 0.4064 0.4064)
			(layers "F.Cu" "F.Mask" "F.Paste")
			(net "FM_ADR_ACK_R")
		)
		(pad "AA3" smd circle
			(at -6.800088 7.599934 90)
			(size 0.4064 0.4064)
			(layers "F.Cu" "F.Mask" "F.Paste")
			(net "FM_ADR_MODE0_R")
		)
		(pad "AA4" smd circle
			(at -5.999988 7.599934 90)
			(size 0.4064 0.4064)
			(layers "F.Cu" "F.Mask" "F.Paste")
			(net "IRQ_PVCCD_CPU0_VRHOT_LVC3_N")
		)
		(pad "AA5" smd circle
			(at -5.199888 7.599934 90)
			(size 0.4064 0.4064)
			(layers "F.Cu" "F.Mask" "F.Paste")
			(net "PWRGD_PLT_AUX_CPU0_LVT3_R")
		)
		(pad "AA6" smd circle
			(at -4.400042 7.599934 90)
			(size 0.4064 0.4064)
			(layers "F.Cu" "F.Mask" "F.Paste")
			(net "RST_MB_STBY_R_N")
		)
		(pad "AA7" smd circle
			(at -3.599942 7.599934 90)
			(size 0.4064 0.4064)
			(layers "F.Cu" "F.Mask" "F.Paste")
			(net "FM_DIS_PS_PWROK_DLY")
		)
		(pad "AA8" smd circle
			(at -2.800096 7.599934 90)
			(size 0.4064 0.4064)
			(layers "F.Cu" "F.Mask" "F.Paste")
			(net "FM_CPU_RMCA_CATERR_LVT3_R_N")
		)
		(pad "AA9" smd circle
			(at -1.999996 7.599934 90)
			(size 0.4064 0.4064)
			(layers "F.Cu" "F.Mask" "F.Paste")
			(net "JTAG_DBP_BMC_PRDY_R_N")
		)
		(pad "AA10" smd circle
			(at -1.199896 7.599934 90)
			(size 0.4064 0.4064)
			(layers "F.Cu" "F.Mask" "F.Paste")
			(net "CLK_25M_OSC_MAIN_FPGA")
		)
		(pad "AA11" smd circle
			(at -0.40005 7.599934 90)
			(size 0.4064 0.4064)
			(layers "F.Cu" "F.Mask" "F.Paste")
			(net "PRSNT_CABLE_GPU_B3_ISO_R_N")
		)
		(pad "AA12" smd circle
			(at 0.40005 7.599934 90)
			(size 0.4064 0.4064)
			(layers "F.Cu" "F.Mask" "F.Paste")
			(net "IRQ_PSYS_CRIT_N")
		)
		(pad "AA13" smd circle
			(at 1.199896 7.599934 90)
			(size 0.4064 0.4064)
			(layers "F.Cu" "F.Mask" "F.Paste")
			(net "IRQ_PVCCD_CPU1_VRHOT_LVC3_N")
		)
		(pad "AA14" smd circle
			(at 1.999996 7.599934 90)
			(size 0.4064 0.4064)
			(layers "F.Cu" "F.Mask" "F.Paste")
			(net "FM_SYS_THROTTLE_R_N")
		)
		(pad "AA15" smd circle
			(at 2.800096 7.599934 90)
			(size 0.4064 0.4064)
			(layers "F.Cu" "F.Mask" "F.Paste")
			(net "NC_FPGA_PB35B")
		)
		(pad "AA16" smd circle
			(at 3.599942 7.599934 90)
			(size 0.4064 0.4064)
			(layers "F.Cu" "F.Mask" "F.Paste")
			(net "FM_PCH_PLD_GLB_RST_WARN_N")
		)
		(pad "AA17" smd circle
			(at 4.400042 7.599934 90)
			(size 0.4064 0.4064)
			(layers "F.Cu" "F.Mask" "F.Paste")
			(net "FM_BMC_READY_R_PLD_N")
		)
		(pad "AA18" smd circle
			(at 5.199888 7.599934 90)
			(size 0.4064 0.4064)
			(layers "F.Cu" "F.Mask" "F.Paste")
			(net "CLK_GPU_1_OE_N")
		)
		(pad "AA19" smd circle
			(at 5.999988 7.599934 90)
			(size 0.4064 0.4064)
			(layers "F.Cu" "F.Mask" "F.Paste")
			(net "FM_PLD_REV_N")
		)
		(pad "AA20" smd circle
			(at 6.800088 7.599934 90)
			(size 0.4064 0.4064)
			(layers "F.Cu" "F.Mask" "F.Paste")
			(net "HPDB_HSC_PWRGD_ISO_R")
		)
		(pad "AA21" smd circle
			(at 7.599934 7.599934 90)
			(size 0.4064 0.4064)
			(layers "F.Cu" "F.Mask" "F.Paste")
			(net "NC_FPGA_PB46B")
		)
		(pad "AA22" smd circle
			(at 8.400034 7.599934 90)
			(size 0.4064 0.4064)
			(layers "F.Cu" "F.Mask" "F.Paste")
			(net "LED_HDD_ACTIVITY_B_PLD_N")
		)
		(pad "AB1" smd circle
			(at -8.400034 8.400034 90)
			(size 0.4064 0.4064)
			(layers "F.Cu" "F.Mask" "F.Paste")
			(net "GND")
		)
		(pad "AB2" smd circle
			(at -7.599934 8.400034 90)
			(size 0.4064 0.4064)
			(layers "F.Cu" "F.Mask" "F.Paste")
			(net "FM_UV_ADR_TRIGGER_R_N")
		)
		(pad "AB3" smd circle
			(at -6.800088 8.400034 90)
			(size 0.4064 0.4064)
			(layers "F.Cu" "F.Mask" "F.Paste")
			(net "FM_ADR_MODE1_R")
		)
		(pad "AB4" smd circle
			(at -5.999988 8.400034 90)
			(size 0.4064 0.4064)
			(layers "F.Cu" "F.Mask" "F.Paste")
			(net "IRQ_BMC_PCH_NMI_R")
		)
		(pad "AB5" smd circle
			(at -5.199888 8.400034 90)
			(size 0.4064 0.4064)
			(layers "F.Cu" "F.Mask" "F.Paste")
			(net "PWRGD_PLT_AUX_CPU1_LVT3_R")
		)
		(pad "AB6" smd circle
			(at -4.400042 8.400034 90)
			(size 0.4064 0.4064)
			(layers "F.Cu" "F.Mask" "F.Paste")
			(net "RST_SMB_SWITCH_N")
		)
		(pad "AB7" smd circle
			(at -3.599942 8.400034 90)
			(size 0.4064 0.4064)
			(layers "F.Cu" "F.Mask" "F.Paste")
			(net "FM_PCH_CRASHLOG_TRIG_R_N")
		)
		(pad "AB8" smd circle
			(at -2.800096 8.400034 90)
			(size 0.4064 0.4064)
			(layers "F.Cu" "F.Mask" "F.Paste")
			(net "FM_PCH_BMC_THERMTRIP_N")
		)
		(pad "AB9" smd circle
			(at -1.999996 8.400034 90)
			(size 0.4064 0.4064)
			(layers "F.Cu" "F.Mask" "F.Paste")
			(net "FM_DEBUG_PORT_PRSNT_N")
		)
		(pad "AB10" smd circle
			(at -1.199896 8.400034 90)
			(size 0.4064 0.4064)
			(layers "F.Cu" "F.Mask" "F.Paste")
			(net "NC_FPGA_PB22B")
		)
		(pad "AB11" smd circle
			(at -0.40005 8.400034 90)
			(size 0.4064 0.4064)
			(layers "F.Cu" "F.Mask" "F.Paste")
			(net "GPU_3V3IO_RSVD3_FFU_ISO_R")
		)
		(pad "AB12" smd circle
			(at 0.40005 8.400034 90)
			(size 0.4064 0.4064)
			(layers "F.Cu" "F.Mask" "F.Paste")
			(net "IRQ_SGPIO_INTR_N_R")
		)
		(pad "AB13" smd circle
			(at 1.199896 8.400034 90)
			(size 0.4064 0.4064)
			(layers "F.Cu" "F.Mask" "F.Paste")
			(net "IRQ_TPM_SPI_N")
		)
		(pad "AB14" smd circle
			(at 1.999996 8.400034 90)
			(size 0.4064 0.4064)
			(layers "F.Cu" "F.Mask" "F.Paste")
			(net "RST_PLTRST_PLD_B_N")
		)
		(pad "AB15" smd circle
			(at 2.800096 8.400034 90)
			(size 0.4064 0.4064)
			(layers "F.Cu" "F.Mask" "F.Paste")
			(net "FM_SPD_REMOTE_EN_R")
		)
		(pad "AB16" smd circle
			(at 3.599942 8.400034 90)
			(size 0.4064 0.4064)
			(layers "F.Cu" "F.Mask" "F.Paste")
			(net "VIRTUAL_RESEAT")
		)
		(pad "AB17" smd circle
			(at 4.400042 8.400034 90)
			(size 0.4064 0.4064)
			(layers "F.Cu" "F.Mask" "F.Paste")
			(net "FM_PCHHOT_R_N")
		)
		(pad "AB18" smd circle
			(at 5.199888 8.400034 90)
			(size 0.4064 0.4064)
			(layers "F.Cu" "F.Mask" "F.Paste")
			(net "JTAG_DBP_BMC_PREQ_R_N")
		)
		(pad "AB19" smd circle
			(at 5.999988 8.400034 90)
			(size 0.4064 0.4064)
			(layers "F.Cu" "F.Mask" "F.Paste")
			(net "CLK_GEN2_BMC_RC_OE_N")
		)
		(pad "AB20" smd circle
			(at 6.800088 8.400034 90)
			(size 0.4064 0.4064)
			(layers "F.Cu" "F.Mask" "F.Paste")
			(net "HGX_DETECT_N_R")
		)
		(pad "AB21" smd circle
			(at 7.599934 8.400034 90)
			(size 0.4064 0.4064)
			(layers "F.Cu" "F.Mask" "F.Paste")
			(net "PULL_FPGA_PB46A")
		)
		(pad "AB22" smd circle
			(at 8.400034 8.400034 90)
			(size 0.4064 0.4064)
			(layers "F.Cu" "F.Mask" "F.Paste")
			(net "GND")
		)
		(pad "B1" smd circle
			(at -8.400034 -7.599934 90)
			(size 0.4064 0.4064)
			(layers "F.Cu" "F.Mask" "F.Paste")
			(net "FM_SWB_PWR_EN")
		)
		(pad "B2" smd circle
			(at -7.599934 -7.599934 90)
			(size 0.4064 0.4064)
			(layers "F.Cu" "F.Mask" "F.Paste")
			(net "FM_FAN_PWR_EN")
		)
		(pad "B3" smd circle
			(at -6.800088 -7.599934 90)
			(size 0.4064 0.4064)
			(layers "F.Cu" "F.Mask" "F.Paste")
			(net "FM_SWB_BIC_READY_ISO_R_N")
		)
		(pad "B4" smd circle
			(at -5.999988 -7.599934 90)
			(size 0.4064 0.4064)
			(layers "F.Cu" "F.Mask" "F.Paste")
			(net "FM_PCH_PRSNT_N")
		)
		(pad "B5" smd circle
			(at -5.199888 -7.599934 90)
			(size 0.4064 0.4064)
			(layers "F.Cu" "F.Mask" "F.Paste")
			(net "IRQ_HSC_FAULT_R1_N")
		)
		(pad "B6" smd circle
			(at -4.400042 -7.599934 90)
			(size 0.4064 0.4064)
			(layers "F.Cu" "F.Mask" "F.Paste")
			(net "FM_OCP_V3_2_PWR_GOOD_R")
		)
		(pad "B7" smd circle
			(at -3.599942 -7.599934 90)
			(size 0.4064 0.4064)
			(layers "F.Cu" "F.Mask" "F.Paste")
			(net "GND")
		)
		(pad "B8" smd circle
			(at -2.800096 -7.599934 90)
			(size 0.4064 0.4064)
			(layers "F.Cu" "F.Mask" "F.Paste")
			(net "IRQ_SML0_ALERT_R_N")
		)
		(pad "B9" smd circle
			(at -1.999996 -7.599934 90)
			(size 0.4064 0.4064)
			(layers "F.Cu" "F.Mask" "F.Paste")
			(net "GPU_FPGA_THERM_OVERT_ISO_R_N")
		)
		(pad "B10" smd circle
			(at -1.199896 -7.599934 90)
			(size 0.4064 0.4064)
			(layers "F.Cu" "F.Mask" "F.Paste")
			(net "SMB_HOST_3V3AUX_PLD_SDA")
		)
		(pad "B11" smd circle
			(at -0.40005 -7.599934 90)
			(size 0.4064 0.4064)
			(layers "F.Cu" "F.Mask" "F.Paste")
			(net "GPU_FPGA_OVERT_ISO_R_N")
		)
		(pad "B12" smd circle
			(at 0.40005 -7.599934 90)
			(size 0.4064 0.4064)
			(layers "F.Cu" "F.Mask" "F.Paste")
			(net "SMB_1_PLD_3V3AUX_SCL_R1")
		)
		(pad "B13" smd circle
			(at 1.199896 -7.599934 90)
			(size 0.4064 0.4064)
			(layers "F.Cu" "F.Mask" "F.Paste")
			(net "PWRGD_PVNN_PCH_AUX")
		)
		(pad "B14" smd circle
			(at 1.999996 -7.599934 90)
			(size 0.4064 0.4064)
			(layers "F.Cu" "F.Mask" "F.Paste")
			(net "FM_NCSI_OCP_V3_2_R_OE")
		)
		(pad "B15" smd circle
			(at 2.800096 -7.599934 90)
			(size 0.4064 0.4064)
			(layers "F.Cu" "F.Mask" "F.Paste")
			(net "SGPIO_DEBUG_PLD_CLK")
		)
		(pad "B16" smd circle
			(at 3.599942 -7.599934 90)
			(size 0.4064 0.4064)
			(layers "F.Cu" "F.Mask" "F.Paste")
			(net "GND")
		)
		(pad "B17" smd circle
			(at 4.400042 -7.599934 90)
			(size 0.4064 0.4064)
			(layers "F.Cu" "F.Mask" "F.Paste")
			(net "SGPIO_OCP_SFF_CLK")
		)
		(pad "B18" smd circle
			(at 5.199888 -7.599934 90)
			(size 0.4064 0.4064)
			(layers "F.Cu" "F.Mask" "F.Paste")
			(net "SGPIO_OCP_V3_2_CLK")
		)
		(pad "B19" smd circle
			(at 5.999988 -7.599934 90)
			(size 0.4064 0.4064)
			(layers "F.Cu" "F.Mask" "F.Paste")
			(net "PU_MAIN_FPGA_CONFIG_DONE")
		)
		(pad "B20" smd circle
			(at 6.800088 -7.599934 90)
			(size 0.4064 0.4064)
			(layers "F.Cu" "F.Mask" "F.Paste")
			(net "P12V_HSC_T_CRIT_R_N")
		)
		(pad "B21" smd circle
			(at 7.599934 -7.599934 90)
			(size 0.4064 0.4064)
			(layers "F.Cu" "F.Mask" "F.Paste")
			(net "NC_FPGA_PT43B")
		)
		(pad "B22" smd circle
			(at 8.400034 -7.599934 90)
			(size 0.4064 0.4064)
			(layers "F.Cu" "F.Mask" "F.Paste")
			(net "NC_FPGA_PT44B")
		)
		(pad "C1" smd circle
			(at -8.400034 -6.800088 90)
			(size 0.4064 0.4064)
			(layers "F.Cu" "F.Mask" "F.Paste")
			(net "RST_PLD_CPU0_DRAM_AB_N")
		)
		(pad "C2" smd circle
			(at -7.599934 -6.800088 90)
			(size 0.4064 0.4064)
			(layers "F.Cu" "F.Mask" "F.Paste")
			(net "GND")
		)
		(pad "C3" smd circle
			(at -6.800088 -6.800088 90)
			(size 0.4064 0.4064)
			(layers "F.Cu" "F.Mask" "F.Paste")
			(net "BIC_MONITER_ISO_R")
		)
		(pad "C4" smd circle
			(at -5.999988 -6.800088 90)
			(size 0.4064 0.4064)
			(layers "F.Cu" "F.Mask" "F.Paste")
			(net "BMC_MONITER")
		)
		(pad "C5" smd circle
			(at -5.199888 -6.800088 90)
			(size 0.4064 0.4064)
			(layers "F.Cu" "F.Mask" "F.Paste")
			(net "FM_BMC_SUSACK_R_N")
		)
		(pad "C6" smd circle
			(at -4.400042 -6.800088 90)
			(size 0.4064 0.4064)
			(layers "F.Cu" "F.Mask" "F.Paste")
			(net "FM_S3M_CPU0_CPLD_CRC_ERROR")
		)
		(pad "C7" smd circle
			(at -3.599942 -6.800088 90)
			(size 0.4064 0.4064)
			(layers "F.Cu" "F.Mask" "F.Paste")
			(net "P3V3_AUX_FPGA_VCCIO0")
		)
		(pad "C8" smd circle
			(at -2.800096 -6.800088 90)
			(size 0.4064 0.4064)
			(layers "F.Cu" "F.Mask" "F.Paste")
			(net "OCP_SFF_CLK_OE_R_N")
		)
		(pad "C9" smd circle
			(at -1.999996 -6.800088 90)
			(size 0.4064 0.4064)
			(layers "F.Cu" "F.Mask" "F.Paste")
			(net "FM_SLP_SUS_RSM_RST_N")
		)
		(pad "C10" smd circle
			(at -1.199896 -6.800088 90)
			(size 0.4064 0.4064)
			(layers "F.Cu" "F.Mask" "F.Paste")
			(net "JTAG_PLD_TMS_R")
		)
		(pad "C11" smd circle
			(at -0.40005 -6.800088 90)
			(size 0.4064 0.4064)
			(layers "F.Cu" "F.Mask" "F.Paste")
			(net "GND")
		)
		(pad "C12" smd circle
			(at 0.40005 -6.800088 90)
			(size 0.4064 0.4064)
			(layers "F.Cu" "F.Mask" "F.Paste")
			(net "P3V3_AUX_FPGA_VCCIO0")
		)
		(pad "C13" smd circle
			(at 1.199896 -6.800088 90)
			(size 0.4064 0.4064)
			(layers "F.Cu" "F.Mask" "F.Paste")
			(net "PWRGD_PVNN_MAIN_CPU1")
		)
		(pad "C14" smd circle
			(at 1.999996 -6.800088 90)
			(size 0.4064 0.4064)
			(layers "F.Cu" "F.Mask" "F.Paste")
			(net "SGPIO_BMC_DOUT")
		)
		(pad "C15" smd circle
			(at 2.800096 -6.800088 90)
			(size 0.4064 0.4064)
			(layers "F.Cu" "F.Mask" "F.Paste")
			(net "SGPIO_DEBUG_PLD_DIN")
		)
		(pad "C16" smd circle
			(at 3.599942 -6.800088 90)
			(size 0.4064 0.4064)
			(layers "F.Cu" "F.Mask" "F.Paste")
			(net "P3V3_AUX_FPGA_VCCIO0")
		)
	)
)
